FILE_TYPE=LIBRARY_PARTS;
TIME=' Created/Modified on Tue Oct 09 14:08:20 2001' ;
primitive 'DIODE2A_DUAL','DIODE2A_DUAL_SOT23';
  pin
    'C':
      PIN_NUMBER='(3)';
      PINUSE='UNSPEC';
      NO_LOAD_CHECK='BOTH';
      NO_IO_CHECK='BOTH';
      ALLOW_CONNECT='TRUE';
    'A1':
      PIN_NUMBER='(1)';
      PINUSE='UNSPEC';
      NO_LOAD_CHECK='BOTH';
      NO_IO_CHECK='BOTH';
      ALLOW_CONNECT='TRUE';
    'A2':
      PIN_NUMBER='(2)';
      PINUSE='UNSPEC';
      NO_LOAD_CHECK='BOTH';
      NO_IO_CHECK='BOTH';
      ALLOW_CONNECT='TRUE';
  end_pin;
  body
    PART_NAME='DIODE2A_DUAL';
    PHYS_DES_PREFIX='CR';
  end_body;
end_primitive;
primitive 'DIODE2A_DUAL_SOT404','DIODE2A_DUAL_SOT404LF';
  pin
    'C':
      PIN_NUMBER='(4)';
      PINUSE='UNSPEC';
      NO_LOAD_CHECK='BOTH';
      NO_IO_CHECK='BOTH';
      ALLOW_CONNECT='TRUE';
    'A1':
      PIN_NUMBER='(1)';
      PINUSE='UNSPEC';
      NO_LOAD_CHECK='BOTH';
      NO_IO_CHECK='BOTH';
      ALLOW_CONNECT='TRUE';
    'A2':
      PIN_NUMBER='(3)';
      PINUSE='UNSPEC';
      NO_LOAD_CHECK='BOTH';
      NO_IO_CHECK='BOTH';
      ALLOW_CONNECT='TRUE';
  end_pin;
  body
    PART_NAME='DIODE2A_DUAL';
    PHYS_DES_PREFIX='CR';
  end_body;
end_primitive;
primitive 'DIODE2A_DUAL_SOT369';
    pin
      'C':
        PIN_NUMBER='(4)';
        PINUSE='UNSPEC';
        NO_LOAD_CHECK='BOTH';
        NO_IO_CHECK='BOTH';
        ALLOW_CONNECT='TRUE';
      'A1':
        PIN_NUMBER='(1)';
        PINUSE='UNSPEC';
        NO_LOAD_CHECK='BOTH';
        NO_IO_CHECK='BOTH';
        ALLOW_CONNECT='TRUE';
      'A2':
        PIN_NUMBER='(3)';
        PINUSE='UNSPEC';
        NO_LOAD_CHECK='BOTH';
        NO_IO_CHECK='BOTH';
        ALLOW_CONNECT='TRUE';
    end_pin;
    body
      PART_NAME='DIODE2A_DUAL';
      PHYS_DES_PREFIX='CR';
  end_body;
end_primitive;
END.
